(kicad_pcb
	(version 20260206)
	(generator "pcbnew")
	(generator_version "10.0")
	(general
		(thickness 1.6)
		(legacy_teardrops no)
	)
	(paper "A4")
	(title_block
		(title "Wiwynn_Tioga_Pass_MB.brd")
		(comment 1 "Tioga Pass / footprints 1681-1688 of 4770")
	)
	(layers
		(0 "F.Cu" signal "TOP")
		(4 "In1.Cu" signal "L2GND")
		(6 "In2.Cu" signal "L3")
		(8 "In3.Cu" signal "L4GND")
		(10 "In4.Cu" signal "L5")
		(12 "In5.Cu" signal "L6GND")
		(14 "In6.Cu" signal "L7VCC")
		(16 "In7.Cu" signal "L8VCC")
		(18 "In8.Cu" signal "L9GND")
		(20 "In9.Cu" signal "L10")
		(22 "In10.Cu" signal "L11GND")
		(24 "In11.Cu" signal "L12")
		(26 "In12.Cu" signal "L13GND")
		(2 "B.Cu" signal "BOTTOM")
		(9 "F.Adhes" user "F.Adhesive")
		(11 "B.Adhes" user "B.Adhesive")
		(13 "F.Paste" user "Package Geometry/Pastemask Top")
		(15 "B.Paste" user "Package Geometry/Pastemask Bottom")
		(5 "F.SilkS" user "Ref Des/Silkscreen Top")
		(7 "B.SilkS" user "Ref Des/Silkscreen Bottom")
		(1 "F.Mask" user "Board Geometry/Soldermask Top")
		(3 "B.Mask" user "Board Geometry/Soldermask Bottom")
		(17 "Dwgs.User" user "User.Drawings")
		(19 "Cmts.User" user "User.Comments")
		(21 "Eco1.User" user "User.Eco1")
		(23 "Eco2.User" user "User.Eco2")
		(25 "Edge.Cuts" user "Board Geometry/Outline")
		(27 "Margin" user)
		(31 "F.CrtYd" user "Package Geometry/Place Bound Top")
		(29 "B.CrtYd" user "Package Geometry/Place Bound Bottom")
		(35 "F.Fab" user "Ref Des/Assembly Top")
		(33 "B.Fab" user "Ref Des/Assembly Bottom")
	)
	(footprint ""
		(layer "F.Cu")
		(at 342.646 -137.1727 90)
		(property "Reference" "R7A15"
			(at 0 0 90)
			(layer "F.SilkS")
			(hide yes)
			(effects
				(font
					(size 1.27 1.27)
				)
			)
		)
		(property "Value" ""
			(at 0 0 90)
			(layer "F.Fab")
			(effects
				(font
					(size 1.27 1.27)
				)
			)
		)
		(duplicate_pad_numbers_are_jumpers no)
		(fp_poly
			(pts
				(xy -0.2794 -0.1016) (xy 0.2794 -0.1016) (xy 0.2794 0.9906) (xy -0.2794 0.9906)
			)
			(stroke
				(width 0)
				(type default)
			)
			(fill no)
			(layer "F.CrtYd")
		)
		(fp_line
			(start 0.2794 -0.1016)
			(end -0.2794 -0.1016)
			(stroke
				(width 0.1)
				(type default)
			)
			(layer "F.Fab")
		)
		(fp_line
			(start -0.2794 -0.1016)
			(end -0.2794 0.9906)
			(stroke
				(width 0.1)
				(type default)
			)
			(layer "F.Fab")
		)
		(fp_line
			(start 0.2794 0.9906)
			(end 0.2794 -0.1016)
			(stroke
				(width 0.1)
				(type default)
			)
			(layer "F.Fab")
		)
		(fp_line
			(start -0.2794 0.9906)
			(end 0.2794 0.9906)
			(stroke
				(width 0.1)
				(type default)
			)
			(layer "F.Fab")
		)
		(pad "1" smd rect
			(at 0 0 90)
			(size 0.508 0.508)
			(layers "F.Cu" "F.Mask" "F.Paste")
			(net "VR_PVPP_DEF_SNUB")
		)
		(pad "2" smd rect
			(at 0 0.889 90)
			(size 0.508 0.508)
			(layers "F.Cu" "F.Mask" "F.Paste")
			(net "GND")
		)
		(zone
			(layer "F.Cu")
			(hatch none 0.5)
			(connect_pads
				(clearance 0)
			)
			(min_thickness 0.25)
			(keepout
				(tracks allowed)
				(vias not_allowed)
				(pads allowed)
				(copperpour not_allowed)
				(footprints allowed)
			)
			(placement
				(enabled no)
				(sheetname "")
			)
			(fill
				(thermal_gap 0.5)
				(thermal_bridge_width 0.5)
				(island_removal_mode 0)
			)
			(polygon
				(pts
					(xy 342.9 -136.9187) (xy 342.9 -137.4267) (xy 343.281 -137.4267) (xy 343.281 -136.9187)
				)
			)
		)
		(zone
			(layer "F.Cu")
			(hatch none 0.5)
			(connect_pads
				(clearance 0)
			)
			(min_thickness 0.25)
			(keepout
				(tracks not_allowed)
				(vias allowed)
				(pads allowed)
				(copperpour not_allowed)
				(footprints allowed)
			)
			(placement
				(enabled no)
				(sheetname "")
			)
			(fill
				(thermal_gap 0.5)
				(thermal_bridge_width 0.5)
				(island_removal_mode 0)
			)
			(polygon
				(pts
					(xy 343.281 -136.9187) (xy 343.281 -137.4267) (xy 342.9 -137.4267) (xy 342.9 -136.9187)
				)
			)
		)
	)
	(footprint ""
		(layer "F.Cu")
		(at 14.224 -77.216 180)
		(property "Reference" "R1D31"
			(at 0 0 180)
			(layer "F.SilkS")
			(hide yes)
			(effects
				(font
					(size 1.27 1.27)
				)
			)
		)
		(property "Value" ""
			(at 0 0 180)
			(layer "F.Fab")
			(effects
				(font
					(size 1.27 1.27)
				)
			)
		)
		(duplicate_pad_numbers_are_jumpers no)
		(fp_rect
			(start 0.2794 0.9906)
			(end -0.2794 -0.1016)
			(stroke
				(width 0)
				(type default)
			)
			(fill no)
			(layer "F.CrtYd")
		)
		(fp_line
			(start 0.2794 0.9906)
			(end 0.2794 -0.1016)
			(stroke
				(width 0.1)
				(type default)
			)
			(layer "F.Fab")
		)
		(fp_line
			(start 0.2794 -0.1016)
			(end -0.2794 -0.1016)
			(stroke
				(width 0.1)
				(type default)
			)
			(layer "F.Fab")
		)
		(fp_line
			(start -0.2794 0.9906)
			(end 0.2794 0.9906)
			(stroke
				(width 0.1)
				(type default)
			)
			(layer "F.Fab")
		)
		(fp_line
			(start -0.2794 -0.1016)
			(end -0.2794 0.9906)
			(stroke
				(width 0.1)
				(type default)
			)
			(layer "F.Fab")
		)
		(pad "1" smd rect
			(at 0 0 180)
			(size 0.508 0.508)
			(layers "F.Cu" "F.Mask" "F.Paste")
			(net "PWRGD_P12V_R")
		)
		(pad "2" smd rect
			(at 0 0.889 180)
			(size 0.508 0.508)
			(layers "F.Cu" "F.Mask" "F.Paste")
			(net "GND")
		)
		(zone
			(layer "F.Cu")
			(hatch none 0.5)
			(connect_pads
				(clearance 0)
			)
			(min_thickness 0.25)
			(keepout
				(tracks not_allowed)
				(vias allowed)
				(pads allowed)
				(copperpour not_allowed)
				(footprints allowed)
			)
			(placement
				(enabled no)
				(sheetname "")
			)
			(fill
				(thermal_gap 0.5)
				(thermal_bridge_width 0.5)
				(island_removal_mode 0)
			)
			(polygon
				(pts
					(xy 13.97 -77.851) (xy 13.97 -77.47) (xy 14.478 -77.47) (xy 14.478 -77.851)
				)
			)
		)
		(zone
			(layer "F.Cu")
			(hatch none 0.5)
			(connect_pads
				(clearance 0)
			)
			(min_thickness 0.25)
			(keepout
				(tracks allowed)
				(vias not_allowed)
				(pads allowed)
				(copperpour not_allowed)
				(footprints allowed)
			)
			(placement
				(enabled no)
				(sheetname "")
			)
			(fill
				(thermal_gap 0.5)
				(thermal_bridge_width 0.5)
				(island_removal_mode 0)
			)
			(polygon
				(pts
					(xy 13.97 -77.851) (xy 13.97 -77.47) (xy 14.478 -77.47) (xy 14.478 -77.851)
				)
			)
		)
	)
	(footprint ""
		(layer "F.Cu")
		(at 193.04 -130.048 -90)
		(property "Reference" "C4B11"
			(at 0 0 270)
			(layer "F.SilkS")
			(hide yes)
			(effects
				(font
					(size 1.27 1.27)
				)
			)
		)
		(property "Value" ""
			(at 0 0 270)
			(layer "F.Fab")
			(effects
				(font
					(size 1.27 1.27)
				)
			)
		)
		(duplicate_pad_numbers_are_jumpers no)
		(fp_rect
			(start -0.7239 1.9939)
			(end 0.7239 -0.2159)
			(stroke
				(width 0)
				(type default)
			)
			(fill no)
			(layer "F.CrtYd")
		)
		(fp_line
			(start -0.7239 1.9939)
			(end 0.7239 1.9939)
			(stroke
				(width 0.1)
				(type default)
			)
			(layer "F.Fab")
		)
		(fp_line
			(start 0.7239 1.9939)
			(end 0.7239 -0.2159)
			(stroke
				(width 0.1)
				(type default)
			)
			(layer "F.Fab")
		)
		(fp_line
			(start -0.7239 -0.2159)
			(end -0.7239 1.9939)
			(stroke
				(width 0.1)
				(type default)
			)
			(layer "F.Fab")
		)
		(fp_line
			(start 0.7239 -0.2159)
			(end -0.7239 -0.2159)
			(stroke
				(width 0.1)
				(type default)
			)
			(layer "F.Fab")
		)
		(pad "1" smd rect
			(at 0 0 270)
			(size 1.27 1.016)
			(layers "F.Cu" "F.Mask" "F.Paste")
			(net "P12V_NVDIMM_DEF")
		)
		(pad "2" smd rect
			(at 0 1.778 270)
			(size 1.27 1.016)
			(layers "F.Cu" "F.Mask" "F.Paste")
			(net "GND")
		)
		(zone
			(layer "F.Cu")
			(hatch none 0.5)
			(connect_pads
				(clearance 0)
			)
			(min_thickness 0.25)
			(keepout
				(tracks not_allowed)
				(vias allowed)
				(pads allowed)
				(copperpour not_allowed)
				(footprints allowed)
			)
			(placement
				(enabled no)
				(sheetname "")
			)
			(fill
				(thermal_gap 0.5)
				(thermal_bridge_width 0.5)
				(island_removal_mode 0)
			)
			(polygon
				(pts
					(xy 191.77 -130.683) (xy 191.77 -129.413) (xy 192.532 -129.413) (xy 192.532 -130.683)
				)
			)
		)
	)
	(footprint ""
		(layer "F.Cu")
		(at 351.630234 -0.12192)
		(property "Reference" "CT54"
			(at -5.15747 -5.207 270)
			(unlocked yes)
			(layer "F.SilkS")
			(effects
				(font
					(size 0.7874 0.5842)
					(thickness 0.1524)
				)
				(justify left)
			)
		)
		(property "Value" ""
			(at 0 0 0)
			(layer "F.Fab")
			(effects
				(font
					(size 1.27 1.27)
				)
			)
		)
		(duplicate_pad_numbers_are_jumpers no)
		(fp_poly
			(pts
				(xy 0.3048 -0.1016) (xy 0.3048 0.9906) (xy -0.3048 0.9906) (xy -0.3048 -0.1016)
			)
			(stroke
				(width 0)
				(type default)
			)
			(fill no)
			(layer "F.CrtYd")
		)
		(fp_line
			(start -0.3048 -0.1016)
			(end -0.3048 0.9906)
			(stroke
				(width 0.1)
				(type default)
			)
			(layer "F.Fab")
		)
		(fp_line
			(start -0.3048 0.9906)
			(end 0.3048 0.9906)
			(stroke
				(width 0.1)
				(type default)
			)
			(layer "F.Fab")
		)
		(fp_line
			(start 0.3048 -0.1016)
			(end -0.3048 -0.1016)
			(stroke
				(width 0.1)
				(type default)
			)
			(layer "F.Fab")
		)
		(fp_line
			(start 0.3048 0.9906)
			(end 0.3048 -0.1016)
			(stroke
				(width 0.1)
				(type default)
			)
			(layer "F.Fab")
		)
		(pad "1" smd rect
			(at 0 0)
			(size 0.508 0.508)
			(layers "F.Cu" "F.Mask" "F.Paste")
			(net "A_TSENSE_PVDDQ_ABC")
		)
		(pad "2" smd rect
			(at 0 0.889)
			(size 0.508 0.508)
			(layers "F.Cu" "F.Mask" "F.Paste")
			(net "GND")
		)
		(zone
			(layer "F.Cu")
			(hatch none 0.5)
			(connect_pads
				(clearance 0)
			)
			(min_thickness 0.25)
			(keepout
				(tracks allowed)
				(vias not_allowed)
				(pads allowed)
				(copperpour not_allowed)
				(footprints allowed)
			)
			(placement
				(enabled no)
				(sheetname "")
			)
			(fill
				(thermal_gap 0.5)
				(thermal_bridge_width 0.5)
				(island_removal_mode 0)
			)
			(polygon
				(pts
					(xy 351.376234 0.13208) (xy 351.884234 0.13208) (xy 351.884234 0.51308) (xy 351.376234 0.51308)
				)
			)
		)
		(zone
			(layer "F.Cu")
			(hatch none 0.5)
			(connect_pads
				(clearance 0)
			)
			(min_thickness 0.25)
			(keepout
				(tracks not_allowed)
				(vias allowed)
				(pads allowed)
				(copperpour not_allowed)
				(footprints allowed)
			)
			(placement
				(enabled no)
				(sheetname "")
			)
			(fill
				(thermal_gap 0.5)
				(thermal_bridge_width 0.5)
				(island_removal_mode 0)
			)
			(polygon
				(pts
					(xy 351.376234 0.51308) (xy 351.884234 0.51308) (xy 351.884234 0.13208) (xy 351.376234 0.13208)
				)
			)
		)
	)
	(footprint ""
		(layer "F.Cu")
		(at 181.70398 -155.83662 90)
		(property "Reference" "C4W5"
			(at 1.47828 0.78994 0)
			(unlocked yes)
			(layer "F.SilkS")
			(effects
				(font
					(size 0.4064 0.254)
					(thickness 0.1524)
				)
			)
		)
		(property "Value" ""
			(at 0 0 90)
			(layer "F.Fab")
			(effects
				(font
					(size 1.27 1.27)
				)
			)
		)
		(duplicate_pad_numbers_are_jumpers no)
		(fp_poly
			(pts
				(xy -0.7239 -0.2159) (xy 0.7239 -0.2159) (xy 0.7239 1.9939) (xy -0.7239 1.9939)
			)
			(stroke
				(width 0)
				(type default)
			)
			(fill no)
			(layer "F.CrtYd")
		)
		(fp_line
			(start 0.7239 -0.2159)
			(end -0.7239 -0.2159)
			(stroke
				(width 0.1)
				(type default)
			)
			(layer "F.Fab")
		)
		(fp_line
			(start -0.7239 -0.2159)
			(end -0.7239 1.9939)
			(stroke
				(width 0.1)
				(type default)
			)
			(layer "F.Fab")
		)
		(fp_line
			(start 0.7239 1.9939)
			(end 0.7239 -0.2159)
			(stroke
				(width 0.1)
				(type default)
			)
			(layer "F.Fab")
		)
		(fp_line
			(start -0.7239 1.9939)
			(end 0.7239 1.9939)
			(stroke
				(width 0.1)
				(type default)
			)
			(layer "F.Fab")
		)
		(pad "1" smd rect
			(at 0 0 90)
			(size 1.27 1.016)
			(layers "F.Cu" "F.Mask" "F.Paste")
			(net "PVTT_DEF")
		)
		(pad "2" smd rect
			(at 0 1.778 90)
			(size 1.27 1.016)
			(layers "F.Cu" "F.Mask" "F.Paste")
			(net "GND")
		)
		(zone
			(layer "F.Cu")
			(hatch none 0.5)
			(connect_pads
				(clearance 0)
			)
			(min_thickness 0.25)
			(keepout
				(tracks not_allowed)
				(vias allowed)
				(pads allowed)
				(copperpour not_allowed)
				(footprints allowed)
			)
			(placement
				(enabled no)
				(sheetname "")
			)
			(fill
				(thermal_gap 0.5)
				(thermal_bridge_width 0.5)
				(island_removal_mode 0)
			)
			(polygon
				(pts
					(xy 182.21198 -155.20162) (xy 182.21198 -156.47162) (xy 182.97398 -156.47162) (xy 182.97398 -155.20162)
				)
			)
		)
	)
	(footprint ""
		(layer "F.Cu")
		(at 406.908 -23.0505)
		(property "Reference" "R25W88"
			(at -0.8382 -0.67818 0)
			(unlocked yes)
			(layer "F.SilkS")
			(effects
				(font
					(size 0.4064 0.254)
					(thickness 0.1524)
				)
				(justify left)
			)
		)
		(property "Value" ""
			(at 0 0 0)
			(layer "F.Fab")
			(effects
				(font
					(size 1.27 1.27)
				)
			)
		)
		(duplicate_pad_numbers_are_jumpers no)
		(fp_poly
			(pts
				(xy -0.2794 -0.1016) (xy 0.2794 -0.1016) (xy 0.2794 0.9906) (xy -0.2794 0.9906)
			)
			(stroke
				(width 0)
				(type default)
			)
			(fill no)
			(layer "F.CrtYd")
		)
		(fp_line
			(start -0.2794 -0.1016)
			(end -0.2794 0.9906)
			(stroke
				(width 0.1)
				(type default)
			)
			(layer "F.Fab")
		)
		(fp_line
			(start -0.2794 0.9906)
			(end 0.2794 0.9906)
			(stroke
				(width 0.1)
				(type default)
			)
			(layer "F.Fab")
		)
		(fp_line
			(start 0.2794 -0.1016)
			(end -0.2794 -0.1016)
			(stroke
				(width 0.1)
				(type default)
			)
			(layer "F.Fab")
		)
		(fp_line
			(start 0.2794 0.9906)
			(end 0.2794 -0.1016)
			(stroke
				(width 0.1)
				(type default)
			)
			(layer "F.Fab")
		)
		(pad "1" smd rect
			(at 0 0)
			(size 0.508 0.508)
			(layers "F.Cu" "F.Mask" "F.Paste")
			(net "RMII_BMC_SPRNGVLLE_TXEN_R")
		)
		(pad "2" smd rect
			(at 0 0.889)
			(size 0.508 0.508)
			(layers "F.Cu" "F.Mask" "F.Paste")
			(net "RMII_BMC_PCH_SPRNGVLLE_TXEN")
		)
		(zone
			(layer "F.Cu")
			(hatch none 0.5)
			(connect_pads
				(clearance 0)
			)
			(min_thickness 0.25)
			(keepout
				(tracks allowed)
				(vias not_allowed)
				(pads allowed)
				(copperpour not_allowed)
				(footprints allowed)
			)
			(placement
				(enabled no)
				(sheetname "")
			)
			(fill
				(thermal_gap 0.5)
				(thermal_bridge_width 0.5)
				(island_removal_mode 0)
			)
			(polygon
				(pts
					(xy 406.654 -22.7965) (xy 407.162 -22.7965) (xy 407.162 -22.4155) (xy 406.654 -22.4155)
				)
			)
		)
		(zone
			(layer "F.Cu")
			(hatch none 0.5)
			(connect_pads
				(clearance 0)
			)
			(min_thickness 0.25)
			(keepout
				(tracks not_allowed)
				(vias allowed)
				(pads allowed)
				(copperpour not_allowed)
				(footprints allowed)
			)
			(placement
				(enabled no)
				(sheetname "")
			)
			(fill
				(thermal_gap 0.5)
				(thermal_bridge_width 0.5)
				(island_removal_mode 0)
			)
			(polygon
				(pts
					(xy 406.654 -22.4155) (xy 407.162 -22.4155) (xy 407.162 -22.7965) (xy 406.654 -22.7965)
				)
			)
		)
	)
	(footprint ""
		(layer "F.Cu")
		(at 278.427434 -77.382116)
		(property "Reference" "C6D6"
			(at 0 0 0)
			(layer "F.SilkS")
			(hide yes)
			(effects
				(font
					(size 1.27 1.27)
				)
			)
		)
		(property "Value" ""
			(at 0 0 0)
			(layer "F.Fab")
			(effects
				(font
					(size 1.27 1.27)
				)
			)
		)
		(duplicate_pad_numbers_are_jumpers no)
		(fp_poly
			(pts
				(xy -0.4953 -0.2032) (xy 0.4953 -0.2032) (xy 0.4953 1.6002) (xy -0.4953 1.6002)
			)
			(stroke
				(width 0)
				(type default)
			)
			(fill no)
			(layer "F.CrtYd")
		)
		(fp_line
			(start -0.4953 -0.2032)
			(end 0.4953 -0.2032)
			(stroke
				(width 0.1)
				(type default)
			)
			(layer "F.Fab")
		)
		(fp_line
			(start -0.4953 1.6002)
			(end -0.4953 -0.2032)
			(stroke
				(width 0.1)
				(type default)
			)
			(layer "F.Fab")
		)
		(fp_line
			(start 0.4953 -0.2032)
			(end 0.4953 1.6002)
			(stroke
				(width 0.1)
				(type default)
			)
			(layer "F.Fab")
		)
		(fp_line
			(start 0.4953 1.6002)
			(end -0.4953 1.6002)
			(stroke
				(width 0.1)
				(type default)
			)
			(layer "F.Fab")
		)
		(pad "1" smd rect
			(at 0 0)
			(size 0.762 0.889)
			(layers "F.Cu" "F.Mask" "F.Paste")
			(net "PVCCIO_CPU0")
		)
		(pad "2" smd rect
			(at 0 1.397)
			(size 0.762 0.889)
			(layers "F.Cu" "F.Mask" "F.Paste")
			(net "GND")
		)
		(zone
			(layer "F.Cu")
			(hatch none 0.5)
			(connect_pads
				(clearance 0)
			)
			(min_thickness 0.25)
			(keepout
				(tracks not_allowed)
				(vias allowed)
				(pads allowed)
				(copperpour not_allowed)
				(footprints allowed)
			)
			(placement
				(enabled no)
				(sheetname "")
			)
			(fill
				(thermal_gap 0.5)
				(thermal_bridge_width 0.5)
				(island_removal_mode 0)
			)
			(polygon
				(pts
					(xy 278.046434 -76.937616) (xy 278.808434 -76.937616) (xy 278.808434 -76.429616) (xy 278.046434 -76.429616)
				)
			)
		)
	)
	(footprint ""
		(layer "F.Cu")
		(at 343.67216 -21.78812 -90)
		(property "Reference" "R7F21"
			(at -0.8382 -0.67818 270)
			(unlocked yes)
			(layer "F.SilkS")
			(effects
				(font
					(size 0.4064 0.254)
					(thickness 0.1524)
				)
				(justify left)
			)
		)
		(property "Value" ""
			(at 0 0 270)
			(layer "F.Fab")
			(effects
				(font
					(size 1.27 1.27)
				)
			)
		)
		(duplicate_pad_numbers_are_jumpers no)
		(fp_poly
			(pts
				(xy -0.2794 -0.1016) (xy 0.2794 -0.1016) (xy 0.2794 0.9906) (xy -0.2794 0.9906)
			)
			(stroke
				(width 0)
				(type default)
			)
			(fill no)
			(layer "F.CrtYd")
		)
		(fp_line
			(start -0.2794 0.9906)
			(end 0.2794 0.9906)
			(stroke
				(width 0.1)
				(type default)
			)
			(layer "F.Fab")
		)
		(fp_line
			(start 0.2794 0.9906)
			(end 0.2794 -0.1016)
			(stroke
				(width 0.1)
				(type default)
			)
			(layer "F.Fab")
		)
		(fp_line
			(start -0.2794 -0.1016)
			(end -0.2794 0.9906)
			(stroke
				(width 0.1)
				(type default)
			)
			(layer "F.Fab")
		)
		(fp_line
			(start 0.2794 -0.1016)
			(end -0.2794 -0.1016)
			(stroke
				(width 0.1)
				(type default)
			)
			(layer "F.Fab")
		)
		(pad "1" smd rect
			(at 0 0 270)
			(size 0.508 0.508)
			(layers "F.Cu" "F.Mask" "F.Paste")
			(net "FM_PVDDQ_ABC_EN")
		)
		(pad "2" smd rect
			(at 0 0.889 270)
			(size 0.508 0.508)
			(layers "F.Cu" "F.Mask" "F.Paste")
			(net "VR_PVDDQ_ABC_VREN")
		)
		(zone
			(layer "F.Cu")
			(hatch none 0.5)
			(connect_pads
				(clearance 0)
			)
			(min_thickness 0.25)
			(keepout
				(tracks not_allowed)
				(vias allowed)
				(pads allowed)
				(copperpour not_allowed)
				(footprints allowed)
			)
			(placement
				(enabled no)
				(sheetname "")
			)
			(fill
				(thermal_gap 0.5)
				(thermal_bridge_width 0.5)
				(island_removal_mode 0)
			)
			(polygon
				(pts
					(xy 343.03716 -22.04212) (xy 343.03716 -21.53412) (xy 343.41816 -21.53412) (xy 343.41816 -22.04212)
				)
			)
		)
		(zone
			(layer "F.Cu")
			(hatch none 0.5)
			(connect_pads
				(clearance 0)
			)
			(min_thickness 0.25)
			(keepout
				(tracks allowed)
				(vias not_allowed)
				(pads allowed)
				(copperpour not_allowed)
				(footprints allowed)
			)
			(placement
				(enabled no)
				(sheetname "")
			)
			(fill
				(thermal_gap 0.5)
				(thermal_bridge_width 0.5)
				(island_removal_mode 0)
			)
			(polygon
				(pts
					(xy 343.41816 -22.04212) (xy 343.41816 -21.53412) (xy 343.03716 -21.53412) (xy 343.03716 -22.04212)
				)
			)
		)
	)
)
